# BASEBOARD_FAB2 (Tioga Pass) — schematic netlist excerpt (pin names and nets, part order shuffled) for the footprints in the layout excerpt that follows; sources: Cadence DE-HDL packaged netlist, KiCad conversion of Wiwynn_Tioga_Pass_MB.brd

R2T28  RES  33.2 1% CHIP  pkg 0402  page 156 : A = FM_PCH_PWRBTN_R_N ; B = FM_PCH_PWRBTN_N
C8P29  CAP  47UF 4V 20% X6S  pkg 0805  page 76 : A = PVCCIN_CPU1 ; B = GND
C4M1  CAPP  220UF 4V 20% POSCAP  pkg 7343  page 232 : A = PVPP_DEF ; B = GND

(kicad_pcb
	(version 20260206)
	(generator "pcbnew")
	(generator_version "10.0")
	(general
		(thickness 1.6)
		(legacy_teardrops no)
	)
	(paper "A4")
	(title_block
		(title "Wiwynn_Tioga_Pass_MB.brd")
		(comment 1 "Tioga Pass / footprints 4379-4381 of 4770")
	)
	(layers
		(0 "F.Cu" signal "TOP")
		(4 "In1.Cu" signal "L2GND")
		(6 "In2.Cu" signal "L3")
		(8 "In3.Cu" signal "L4GND")
		(10 "In4.Cu" signal "L5")
		(12 "In5.Cu" signal "L6GND")
		(14 "In6.Cu" signal "L7VCC")
		(16 "In7.Cu" signal "L8VCC")
		(18 "In8.Cu" signal "L9GND")
		(20 "In9.Cu" signal "L10")
		(22 "In10.Cu" signal "L11GND")
		(24 "In11.Cu" signal "L12")
		(26 "In12.Cu" signal "L13GND")
		(2 "B.Cu" signal "BOTTOM")
		(9 "F.Adhes" user "F.Adhesive")
		(11 "B.Adhes" user "B.Adhesive")
		(13 "F.Paste" user "Package Geometry/Pastemask Top")
		(15 "B.Paste" user "Package Geometry/Pastemask Bottom")
		(5 "F.SilkS" user "Ref Des/Silkscreen Top")
		(7 "B.SilkS" user "Ref Des/Silkscreen Bottom")
		(1 "F.Mask" user "Board Geometry/Soldermask Top")
		(3 "B.Mask" user "Board Geometry/Soldermask Bottom")
		(17 "Dwgs.User" user "User.Drawings")
		(19 "Cmts.User" user "User.Comments")
		(21 "Eco1.User" user "User.Eco1")
		(23 "Eco2.User" user "User.Eco2")
		(25 "Edge.Cuts" user "Board Geometry/Outline")
		(27 "Margin" user)
		(31 "F.CrtYd" user "Package Geometry/Place Bound Top")
		(29 "B.CrtYd" user "Package Geometry/Place Bound Bottom")
		(35 "F.Fab" user "Ref Des/Assembly Top")
		(33 "B.Fab" user "Ref Des/Assembly Bottom")
	)
	(footprint ""
		(layer "B.Cu")
		(at 396.674086 -30.627574 180)
		(property "Reference" "R2T28"
			(at 0 0 0)
			(layer "B.SilkS")
			(hide yes)
			(effects
				(font
					(size 1.27 1.27)
				)
				(justify mirror)
			)
		)
		(property "Value" ""
			(at 0 0 0)
			(layer "B.Fab")
			(effects
				(font
					(size 1.27 1.27)
				)
				(justify mirror)
			)
		)
		(duplicate_pad_numbers_are_jumpers no)
		(fp_poly
			(pts
				(xy 0.2794 -0.1016) (xy -0.2794 -0.1016) (xy -0.2794 0.9906) (xy 0.2794 0.9906)
			)
			(stroke
				(width 0)
				(type default)
			)
			(fill no)
			(layer "B.CrtYd")
		)
		(fp_line
			(start 0.2794 0.9906)
			(end -0.2794 0.9906)
			(stroke
				(width 0.1)
				(type default)
			)
			(layer "B.Fab")
		)
		(fp_line
			(start 0.2794 -0.1016)
			(end 0.2794 0.9906)
			(stroke
				(width 0.1)
				(type default)
			)
			(layer "B.Fab")
		)
		(fp_line
			(start -0.2794 0.9906)
			(end -0.2794 -0.1016)
			(stroke
				(width 0.1)
				(type default)
			)
			(layer "B.Fab")
		)
		(fp_line
			(start -0.2794 -0.1016)
			(end 0.2794 -0.1016)
			(stroke
				(width 0.1)
				(type default)
			)
			(layer "B.Fab")
		)
		(pad "1" smd rect
			(at 0 0)
			(size 0.508 0.508)
			(layers "B.Cu" "B.Mask" "B.Paste")
			(net "FM_PCH_PWRBTN_R_N")
		)
		(pad "2" smd rect
			(at 0 0.889)
			(size 0.508 0.508)
			(layers "B.Cu" "B.Mask" "B.Paste")
			(net "FM_PCH_PWRBTN_N")
		)
		(zone
			(layer "B.Cu")
			(hatch none 0.5)
			(connect_pads
				(clearance 0)
			)
			(min_thickness 0.25)
			(keepout
				(tracks not_allowed)
				(vias allowed)
				(pads allowed)
				(copperpour not_allowed)
				(footprints allowed)
			)
			(placement
				(enabled no)
				(sheetname "")
			)
			(fill
				(thermal_gap 0.5)
				(thermal_bridge_width 0.5)
				(island_removal_mode 0)
			)
			(polygon
				(pts
					(xy 396.420086 -31.262574) (xy 396.928086 -31.262574) (xy 396.928086 -30.881574) (xy 396.420086 -30.881574)
				)
			)
		)
		(zone
			(layer "B.Cu")
			(hatch none 0.5)
			(connect_pads
				(clearance 0)
			)
			(min_thickness 0.25)
			(keepout
				(tracks allowed)
				(vias not_allowed)
				(pads allowed)
				(copperpour not_allowed)
				(footprints allowed)
			)
			(placement
				(enabled no)
				(sheetname "")
			)
			(fill
				(thermal_gap 0.5)
				(thermal_bridge_width 0.5)
				(island_removal_mode 0)
			)
			(polygon
				(pts
					(xy 396.420086 -30.881574) (xy 396.928086 -30.881574) (xy 396.928086 -31.262574) (xy 396.420086 -31.262574)
				)
			)
		)
	)
	(footprint ""
		(layer "B.Cu")
		(at 331.8002 -135.4074 90)
		(property "Reference" "C4M1"
			(at -3.36423 1.43002 0)
			(unlocked yes)
			(layer "B.SilkS")
			(effects
				(font
					(size 0.7874 0.5842)
					(thickness 0.1524)
				)
				(justify left mirror)
			)
		)
		(property "Value" ""
			(at 0 0 90)
			(layer "B.Fab")
			(effects
				(font
					(size 1.27 1.27)
				)
				(justify mirror)
			)
		)
		(duplicate_pad_numbers_are_jumpers no)
		(fp_line
			(start 2.032 -1.524)
			(end 2.032 1.524)
			(stroke
				(width 0.1524)
				(type default)
			)
			(layer "B.SilkS")
		)
		(fp_line
			(start 1.7272 -1.524)
			(end 2.032 -1.524)
			(stroke
				(width 0.1524)
				(type default)
			)
			(layer "B.SilkS")
		)
		(fp_line
			(start -1.7272 -1.524)
			(end -2.032 -1.524)
			(stroke
				(width 0.1524)
				(type default)
			)
			(layer "B.SilkS")
		)
		(fp_line
			(start -2.032 -1.524)
			(end -2.032 1.524)
			(stroke
				(width 0.1524)
				(type default)
			)
			(layer "B.SilkS")
		)
		(fp_line
			(start 2.2987 -0.2413)
			(end 2.2987 7.3533)
			(stroke
				(width 0.1524)
				(type default)
			)
			(layer "B.SilkS")
		)
		(fp_line
			(start 2.032 -0.2413)
			(end 2.2987 -0.2413)
			(stroke
				(width 0.1524)
				(type default)
			)
			(layer "B.SilkS")
		)
		(fp_line
			(start -2.2987 -0.2413)
			(end -2.032 -0.2413)
			(stroke
				(width 0.1524)
				(type default)
			)
			(layer "B.SilkS")
		)
		(fp_line
			(start 2.032 1.524)
			(end 1.7272 1.524)
			(stroke
				(width 0.1524)
				(type default)
			)
			(layer "B.SilkS")
		)
		(fp_line
			(start -2.032 1.524)
			(end -1.7272 1.524)
			(stroke
				(width 0.1524)
				(type default)
			)
			(layer "B.SilkS")
		)
		(fp_line
			(start 2.2987 7.3533)
			(end 1.7272 7.3533)
			(stroke
				(width 0.1524)
				(type default)
			)
			(layer "B.SilkS")
		)
		(fp_line
			(start -1.7272 7.3533)
			(end -2.2987 7.3533)
			(stroke
				(width 0.1524)
				(type default)
			)
			(layer "B.SilkS")
		)
		(fp_line
			(start -2.2987 7.3533)
			(end -2.2987 -0.2413)
			(stroke
				(width 0.1524)
				(type default)
			)
			(layer "B.SilkS")
		)
		(fp_poly
			(pts
				(xy 2.2987 -0.2413) (xy -2.2987 -0.2413) (xy -2.2987 7.3533) (xy 2.2987 7.3533)
			)
			(stroke
				(width 0)
				(type default)
			)
			(fill no)
			(layer "B.CrtYd")
		)
		(fp_line
			(start 2.2987 -0.2413)
			(end -2.2987 -0.2413)
			(stroke
				(width 0.1)
				(type default)
			)
			(layer "B.Fab")
		)
		(fp_line
			(start -2.2987 -0.2413)
			(end -2.2987 7.3533)
			(stroke
				(width 0.1)
				(type default)
			)
			(layer "B.Fab")
		)
		(fp_line
			(start 2.2987 7.3533)
			(end 2.2987 -0.2413)
			(stroke
				(width 0.1)
				(type default)
			)
			(layer "B.Fab")
		)
		(fp_line
			(start -2.2987 7.3533)
			(end 2.2987 7.3533)
			(stroke
				(width 0.1)
				(type default)
			)
			(layer "B.Fab")
		)
		(pad "1" smd rect
			(at 0 0 270)
			(size 2.54 3.048)
			(layers "B.Cu" "B.Mask" "B.Paste")
			(net "PVPP_DEF")
		)
		(pad "2" smd rect
			(at 0 7.112 270)
			(size 2.54 3.048)
			(layers "B.Cu" "B.Mask" "B.Paste")
			(net "GND")
		)
	)
	(footprint ""
		(layer "B.Cu")
		(at 93.548454 -73.51014)
		(property "Reference" "C8P29"
			(at 0 0 0)
			(layer "B.SilkS")
			(hide yes)
			(effects
				(font
					(size 1.27 1.27)
				)
				(justify mirror)
			)
		)
		(property "Value" ""
			(at 0 0 0)
			(layer "B.Fab")
			(effects
				(font
					(size 1.27 1.27)
				)
				(justify mirror)
			)
		)
		(duplicate_pad_numbers_are_jumpers no)
		(fp_poly
			(pts
				(xy 0.7239 -0.2159) (xy -0.7239 -0.2159) (xy -0.7239 1.9939) (xy 0.7239 1.9939)
			)
			(stroke
				(width 0)
				(type default)
			)
			(fill no)
			(layer "B.CrtYd")
		)
		(fp_line
			(start -0.7239 -0.2159)
			(end 0.7239 -0.2159)
			(stroke
				(width 0.1)
				(type default)
			)
			(layer "B.Fab")
		)
		(fp_line
			(start -0.7239 1.9939)
			(end -0.7239 -0.2159)
			(stroke
				(width 0.1)
				(type default)
			)
			(layer "B.Fab")
		)
		(fp_line
			(start 0.7239 -0.2159)
			(end 0.7239 1.9939)
			(stroke
				(width 0.1)
				(type default)
			)
			(layer "B.Fab")
		)
		(fp_line
			(start 0.7239 1.9939)
			(end -0.7239 1.9939)
			(stroke
				(width 0.1)
				(type default)
			)
			(layer "B.Fab")
		)
		(pad "1" smd rect
			(at 0 0 180)
			(size 1.27 1.016)
			(layers "B.Cu" "B.Mask" "B.Paste")
			(net "PVCCIN_CPU1")
		)
		(pad "2" smd rect
			(at 0 1.778 180)
			(size 1.27 1.016)
			(layers "B.Cu" "B.Mask" "B.Paste")
			(net "GND")
		)
		(zone
			(layer "B.Cu")
			(hatch none 0.5)
			(connect_pads
				(clearance 0)
			)
			(min_thickness 0.25)
			(keepout
				(tracks not_allowed)
				(vias allowed)
				(pads allowed)
				(copperpour not_allowed)
				(footprints allowed)
			)
			(placement
				(enabled no)
				(sheetname "")
			)
			(fill
				(thermal_gap 0.5)
				(thermal_bridge_width 0.5)
				(island_removal_mode 0)
			)
			(polygon
				(pts
					(xy 94.183454 -73.00214) (xy 92.913454 -73.00214) (xy 92.913454 -72.24014) (xy 94.183454 -72.24014)
				)
			)
		)
	)
)
